(kicad_pcb
	(version 20260206)
	(generator "pcbnew")
	(generator_version "10.0")
	(general
		(thickness 1.6)
		(legacy_teardrops no)
	)
	(paper "A4")
	(title_block
		(title "04192023_DAF0TMB3IC0_F0TG_MB_C_brd_V02_OCP.brd")
		(comment 1 "Grand Teton / footprints 5152-5159 of 8354")
	)
	(layers
		(0 "F.Cu" signal "TOP")
		(4 "In1.Cu" signal "GND")
		(6 "In2.Cu" signal "IN1")
		(8 "In3.Cu" signal "GND1")
		(10 "In4.Cu" signal "IN2")
		(12 "In5.Cu" signal "GND2")
		(14 "In6.Cu" signal "IN3")
		(16 "In7.Cu" signal "GND3")
		(18 "In8.Cu" signal "VCC")
		(20 "In9.Cu" signal "VCC1")
		(22 "In10.Cu" signal "GND4")
		(24 "In11.Cu" signal "IN4")
		(26 "In12.Cu" signal "GND5")
		(28 "In13.Cu" signal "IN5")
		(30 "In14.Cu" signal "GND6")
		(32 "In15.Cu" signal "IN6")
		(34 "In16.Cu" signal "GND7")
		(2 "B.Cu" signal "BOTTOM")
		(9 "F.Adhes" user "F.Adhesive")
		(11 "B.Adhes" user "B.Adhesive")
		(13 "F.Paste" user "Package Geometry/Pastemask Top")
		(15 "B.Paste" user "Package Geometry/Pastemask Bottom")
		(5 "F.SilkS" user "Ref Des/Silkscreen Top")
		(7 "B.SilkS" user "Ref Des/Silkscreen Bottom")
		(1 "F.Mask" user "Board Geometry/Soldermask Top")
		(3 "B.Mask" user "Board Geometry/Soldermask Bottom")
		(17 "Dwgs.User" user "User.Drawings")
		(19 "Cmts.User" user "User.Comments")
		(21 "Eco1.User" user "User.Eco1")
		(23 "Eco2.User" user "User.Eco2")
		(25 "Edge.Cuts" user "Board Geometry/Outline")
		(27 "Margin" user)
		(31 "F.CrtYd" user "Package Geometry/Place Bound Top")
		(29 "B.CrtYd" user "Package Geometry/Place Bound Bottom")
		(35 "F.Fab" user "Ref Des/Assembly Top")
		(33 "B.Fab" user "Ref Des/Assembly Bottom")
	)
	(footprint ""
		(layer "B.Cu")
		(at 115.991386 -249.368564)
		(property "Reference" "C2307"
			(at 0 0 0)
			(layer "B.SilkS")
			(hide yes)
			(effects
				(font
					(size 1.27 1.27)
				)
				(justify mirror)
			)
		)
		(property "Value" ""
			(at 0 0 0)
			(layer "B.Fab")
			(effects
				(font
					(size 1.27 1.27)
				)
				(justify mirror)
			)
		)
		(duplicate_pad_numbers_are_jumpers no)
		(fp_line
			(start -0.7874 -0.4064)
			(end -0.7874 0.4064)
			(stroke
				(width 0.1524)
				(type default)
			)
			(layer "B.SilkS")
		)
		(fp_line
			(start -0.7874 0.4064)
			(end 0.7874 0.4064)
			(stroke
				(width 0.1524)
				(type default)
			)
			(layer "B.SilkS")
		)
		(fp_line
			(start 0.7874 -0.4064)
			(end -0.7874 -0.4064)
			(stroke
				(width 0.1524)
				(type default)
			)
			(layer "B.SilkS")
		)
		(fp_line
			(start 0.7874 0.4064)
			(end 0.7874 -0.4064)
			(stroke
				(width 0.1524)
				(type default)
			)
			(layer "B.SilkS")
		)
		(fp_line
			(start -0.67945 -0.3048)
			(end -0.67945 0.3048)
			(stroke
				(width 0.1)
				(type default)
			)
			(layer "B.Fab")
		)
		(fp_line
			(start -0.67945 0.3048)
			(end -0.120396 0.3048)
			(stroke
				(width 0.1)
				(type default)
			)
			(layer "B.Fab")
		)
		(fp_line
			(start -0.12065 -0.3048)
			(end -0.67945 -0.3048)
			(stroke
				(width 0.1)
				(type default)
			)
			(layer "B.Fab")
		)
		(fp_line
			(start -0.12065 -0.2794)
			(end -0.12065 -0.3048)
			(stroke
				(width 0.1)
				(type default)
			)
			(layer "B.Fab")
		)
		(fp_line
			(start -0.120396 0.2794)
			(end 0.12065 0.2794)
			(stroke
				(width 0.1)
				(type default)
			)
			(layer "B.Fab")
		)
		(fp_line
			(start -0.120396 0.3048)
			(end -0.120396 0.2794)
			(stroke
				(width 0.1)
				(type default)
			)
			(layer "B.Fab")
		)
		(fp_line
			(start 0.12065 -0.305054)
			(end 0.12065 -0.2794)
			(stroke
				(width 0.1)
				(type default)
			)
			(layer "B.Fab")
		)
		(fp_line
			(start 0.12065 -0.2794)
			(end -0.12065 -0.2794)
			(stroke
				(width 0.1)
				(type default)
			)
			(layer "B.Fab")
		)
		(fp_line
			(start 0.12065 0.2794)
			(end 0.12065 0.3048)
			(stroke
				(width 0.1)
				(type default)
			)
			(layer "B.Fab")
		)
		(fp_line
			(start 0.12065 0.3048)
			(end 0.67945 0.3048)
			(stroke
				(width 0.1)
				(type default)
			)
			(layer "B.Fab")
		)
		(fp_line
			(start 0.67945 -0.305054)
			(end 0.12065 -0.305054)
			(stroke
				(width 0.1)
				(type default)
			)
			(layer "B.Fab")
		)
		(fp_line
			(start 0.67945 0.3048)
			(end 0.67945 -0.305054)
			(stroke
				(width 0.1)
				(type default)
			)
			(layer "B.Fab")
		)
		(pad "1" smd circle
			(at 0.40005 0 180)
			(size 0 0)
			(layers "B.Cu" "B.Mask" "B.Paste")
			(net "PVDDCR_CPU0_P1")
		)
		(pad "2" smd circle
			(at -0.40005 0 180)
			(size 0 0)
			(layers "B.Cu" "B.Mask" "B.Paste")
			(net "GND")
		)
	)
	(footprint ""
		(layer "B.Cu")
		(at 455.07783 -48.106838 -90)
		(property "Reference" "R3118"
			(at 0 0 90)
			(layer "B.SilkS")
			(hide yes)
			(effects
				(font
					(size 1.27 1.27)
				)
				(justify mirror)
			)
		)
		(property "Value" ""
			(at 0 0 90)
			(layer "B.Fab")
			(effects
				(font
					(size 1.27 1.27)
				)
				(justify mirror)
			)
		)
		(duplicate_pad_numbers_are_jumpers no)
		(fp_line
			(start -0.7874 0.4064)
			(end 0.7874 0.4064)
			(stroke
				(width 0.1524)
				(type default)
			)
			(layer "B.SilkS")
		)
		(fp_line
			(start 0.7874 0.4064)
			(end 0.7874 -0.4064)
			(stroke
				(width 0.1524)
				(type default)
			)
			(layer "B.SilkS")
		)
		(fp_line
			(start -0.7874 -0.4064)
			(end -0.7874 0.4064)
			(stroke
				(width 0.1524)
				(type default)
			)
			(layer "B.SilkS")
		)
		(fp_line
			(start 0.7874 -0.4064)
			(end -0.7874 -0.4064)
			(stroke
				(width 0.1524)
				(type default)
			)
			(layer "B.SilkS")
		)
		(fp_line
			(start -0.67945 0.3048)
			(end -0.120396 0.3048)
			(stroke
				(width 0.1)
				(type default)
			)
			(layer "B.Fab")
		)
		(fp_line
			(start -0.120396 0.3048)
			(end -0.120396 0.2794)
			(stroke
				(width 0.1)
				(type default)
			)
			(layer "B.Fab")
		)
		(fp_line
			(start 0.12065 0.3048)
			(end 0.67945 0.3048)
			(stroke
				(width 0.1)
				(type default)
			)
			(layer "B.Fab")
		)
		(fp_line
			(start 0.67945 0.3048)
			(end 0.67945 -0.305054)
			(stroke
				(width 0.1)
				(type default)
			)
			(layer "B.Fab")
		)
		(fp_line
			(start -0.120396 0.2794)
			(end 0.12065 0.2794)
			(stroke
				(width 0.1)
				(type default)
			)
			(layer "B.Fab")
		)
		(fp_line
			(start 0.12065 0.2794)
			(end 0.12065 0.3048)
			(stroke
				(width 0.1)
				(type default)
			)
			(layer "B.Fab")
		)
		(fp_line
			(start -0.12065 -0.2794)
			(end -0.12065 -0.3048)
			(stroke
				(width 0.1)
				(type default)
			)
			(layer "B.Fab")
		)
		(fp_line
			(start 0.12065 -0.2794)
			(end -0.12065 -0.2794)
			(stroke
				(width 0.1)
				(type default)
			)
			(layer "B.Fab")
		)
		(fp_line
			(start -0.67945 -0.3048)
			(end -0.67945 0.3048)
			(stroke
				(width 0.1)
				(type default)
			)
			(layer "B.Fab")
		)
		(fp_line
			(start -0.12065 -0.3048)
			(end -0.67945 -0.3048)
			(stroke
				(width 0.1)
				(type default)
			)
			(layer "B.Fab")
		)
		(fp_line
			(start 0.12065 -0.305054)
			(end 0.12065 -0.2794)
			(stroke
				(width 0.1)
				(type default)
			)
			(layer "B.Fab")
		)
		(fp_line
			(start 0.67945 -0.305054)
			(end 0.12065 -0.305054)
			(stroke
				(width 0.1)
				(type default)
			)
			(layer "B.Fab")
		)
		(pad "1" smd circle
			(at 0.40005 0 90)
			(size 0 0)
			(layers "B.Cu" "B.Mask" "B.Paste")
			(net "P3V3_AUX_EN")
		)
		(pad "2" smd circle
			(at -0.40005 0 90)
			(size 0 0)
			(layers "B.Cu" "B.Mask" "B.Paste")
			(net "GND")
		)
	)
	(footprint ""
		(layer "B.Cu")
		(at 49.91862 -388.011162 -90)
		(property "Reference" "C184"
			(at 0 0 90)
			(layer "B.SilkS")
			(hide yes)
			(effects
				(font
					(size 1.27 1.27)
				)
				(justify mirror)
			)
		)
		(property "Value" ""
			(at 0 0 90)
			(layer "B.Fab")
			(effects
				(font
					(size 1.27 1.27)
				)
				(justify mirror)
			)
		)
		(duplicate_pad_numbers_are_jumpers no)
		(fp_line
			(start -0.299974 0.150114)
			(end 0.299974 0.150114)
			(stroke
				(width 0.1)
				(type default)
			)
			(layer "B.Fab")
		)
		(fp_line
			(start 0.299974 0.150114)
			(end 0.299974 -0.150114)
			(stroke
				(width 0.1)
				(type default)
			)
			(layer "B.Fab")
		)
		(fp_line
			(start -0.299974 -0.150114)
			(end -0.299974 0.150114)
			(stroke
				(width 0.1)
				(type default)
			)
			(layer "B.Fab")
		)
		(fp_line
			(start 0.299974 -0.150114)
			(end -0.299974 -0.150114)
			(stroke
				(width 0.1)
				(type default)
			)
			(layer "B.Fab")
		)
		(pad "1" smd rect
			(at 0.2667 0 90)
			(size 0.3048 0.381)
			(layers "B.Cu" "B.Mask" "B.Paste")
			(net "P0V9_CPU1_RT0_2A")
		)
		(pad "2" smd rect
			(at -0.2667 0 90)
			(size 0.3048 0.381)
			(layers "B.Cu" "B.Mask" "B.Paste")
			(net "GND")
		)
	)
	(footprint ""
		(layer "B.Cu")
		(at 101.894386 -255.845564)
		(property "Reference" "C2470"
			(at 0 0 0)
			(layer "B.SilkS")
			(hide yes)
			(effects
				(font
					(size 1.27 1.27)
				)
				(justify mirror)
			)
		)
		(property "Value" ""
			(at 0 0 0)
			(layer "B.Fab")
			(effects
				(font
					(size 1.27 1.27)
				)
				(justify mirror)
			)
		)
		(duplicate_pad_numbers_are_jumpers no)
		(fp_line
			(start -0.7874 -0.4064)
			(end -0.7874 0.4064)
			(stroke
				(width 0.1524)
				(type default)
			)
			(layer "B.SilkS")
		)
		(fp_line
			(start -0.7874 0.4064)
			(end 0.7874 0.4064)
			(stroke
				(width 0.1524)
				(type default)
			)
			(layer "B.SilkS")
		)
		(fp_line
			(start 0.7874 -0.4064)
			(end -0.7874 -0.4064)
			(stroke
				(width 0.1524)
				(type default)
			)
			(layer "B.SilkS")
		)
		(fp_line
			(start 0.7874 0.4064)
			(end 0.7874 -0.4064)
			(stroke
				(width 0.1524)
				(type default)
			)
			(layer "B.SilkS")
		)
		(fp_line
			(start -0.67945 -0.3048)
			(end -0.67945 0.3048)
			(stroke
				(width 0.1)
				(type default)
			)
			(layer "B.Fab")
		)
		(fp_line
			(start -0.67945 0.3048)
			(end -0.120396 0.3048)
			(stroke
				(width 0.1)
				(type default)
			)
			(layer "B.Fab")
		)
		(fp_line
			(start -0.12065 -0.3048)
			(end -0.67945 -0.3048)
			(stroke
				(width 0.1)
				(type default)
			)
			(layer "B.Fab")
		)
		(fp_line
			(start -0.12065 -0.2794)
			(end -0.12065 -0.3048)
			(stroke
				(width 0.1)
				(type default)
			)
			(layer "B.Fab")
		)
		(fp_line
			(start -0.120396 0.2794)
			(end 0.12065 0.2794)
			(stroke
				(width 0.1)
				(type default)
			)
			(layer "B.Fab")
		)
		(fp_line
			(start -0.120396 0.3048)
			(end -0.120396 0.2794)
			(stroke
				(width 0.1)
				(type default)
			)
			(layer "B.Fab")
		)
		(fp_line
			(start 0.12065 -0.305054)
			(end 0.12065 -0.2794)
			(stroke
				(width 0.1)
				(type default)
			)
			(layer "B.Fab")
		)
		(fp_line
			(start 0.12065 -0.2794)
			(end -0.12065 -0.2794)
			(stroke
				(width 0.1)
				(type default)
			)
			(layer "B.Fab")
		)
		(fp_line
			(start 0.12065 0.2794)
			(end 0.12065 0.3048)
			(stroke
				(width 0.1)
				(type default)
			)
			(layer "B.Fab")
		)
		(fp_line
			(start 0.12065 0.3048)
			(end 0.67945 0.3048)
			(stroke
				(width 0.1)
				(type default)
			)
			(layer "B.Fab")
		)
		(fp_line
			(start 0.67945 -0.305054)
			(end 0.12065 -0.305054)
			(stroke
				(width 0.1)
				(type default)
			)
			(layer "B.Fab")
		)
		(fp_line
			(start 0.67945 0.3048)
			(end 0.67945 -0.305054)
			(stroke
				(width 0.1)
				(type default)
			)
			(layer "B.Fab")
		)
		(pad "1" smd circle
			(at 0.40005 0 180)
			(size 0 0)
			(layers "B.Cu" "B.Mask" "B.Paste")
			(net "PVDDCR_SOC_P1")
		)
		(pad "2" smd circle
			(at -0.40005 0 180)
			(size 0 0)
			(layers "B.Cu" "B.Mask" "B.Paste")
			(net "GND")
		)
	)
	(footprint ""
		(layer "B.Cu")
		(at 77.627734 -388.609078 90)
		(property "Reference" "C312"
			(at 0 0 90)
			(layer "B.SilkS")
			(hide yes)
			(effects
				(font
					(size 1.27 1.27)
				)
				(justify mirror)
			)
		)
		(property "Value" ""
			(at 0 0 90)
			(layer "B.Fab")
			(effects
				(font
					(size 1.27 1.27)
				)
				(justify mirror)
			)
		)
		(duplicate_pad_numbers_are_jumpers no)
		(fp_line
			(start 0.299974 -0.150114)
			(end -0.299974 -0.150114)
			(stroke
				(width 0.1)
				(type default)
			)
			(layer "B.Fab")
		)
		(fp_line
			(start -0.299974 -0.150114)
			(end -0.299974 0.150114)
			(stroke
				(width 0.1)
				(type default)
			)
			(layer "B.Fab")
		)
		(fp_line
			(start 0.299974 0.150114)
			(end 0.299974 -0.150114)
			(stroke
				(width 0.1)
				(type default)
			)
			(layer "B.Fab")
		)
		(fp_line
			(start -0.299974 0.150114)
			(end 0.299974 0.150114)
			(stroke
				(width 0.1)
				(type default)
			)
			(layer "B.Fab")
		)
		(pad "1" smd rect
			(at 0.2667 0 270)
			(size 0.3048 0.381)
			(layers "B.Cu" "B.Mask" "B.Paste")
			(net "P0V9_CPU1_RT1_2A")
		)
		(pad "2" smd rect
			(at -0.2667 0 270)
			(size 0.3048 0.381)
			(layers "B.Cu" "B.Mask" "B.Paste")
			(net "GND")
		)
	)
	(footprint ""
		(layer "B.Cu")
		(at 126.911608 -38.87343 90)
		(property "Reference" "C6060"
			(at 0 0 90)
			(layer "B.SilkS")
			(hide yes)
			(effects
				(font
					(size 1.27 1.27)
				)
				(justify mirror)
			)
		)
		(property "Value" ""
			(at 0 0 90)
			(layer "B.Fab")
			(effects
				(font
					(size 1.27 1.27)
				)
				(justify mirror)
			)
		)
		(duplicate_pad_numbers_are_jumpers no)
		(fp_line
			(start 0.7874 -0.4064)
			(end -0.7874 -0.4064)
			(stroke
				(width 0.1524)
				(type default)
			)
			(layer "B.SilkS")
		)
		(fp_line
			(start -0.7874 -0.4064)
			(end -0.7874 0.4064)
			(stroke
				(width 0.1524)
				(type default)
			)
			(layer "B.SilkS")
		)
		(fp_line
			(start 0.7874 0.4064)
			(end 0.7874 -0.4064)
			(stroke
				(width 0.1524)
				(type default)
			)
			(layer "B.SilkS")
		)
		(fp_line
			(start -0.7874 0.4064)
			(end 0.7874 0.4064)
			(stroke
				(width 0.1524)
				(type default)
			)
			(layer "B.SilkS")
		)
		(fp_line
			(start 0.67945 -0.305054)
			(end 0.12065 -0.305054)
			(stroke
				(width 0.1)
				(type default)
			)
			(layer "B.Fab")
		)
		(fp_line
			(start 0.12065 -0.305054)
			(end 0.12065 -0.2794)
			(stroke
				(width 0.1)
				(type default)
			)
			(layer "B.Fab")
		)
		(fp_line
			(start -0.12065 -0.3048)
			(end -0.67945 -0.3048)
			(stroke
				(width 0.1)
				(type default)
			)
			(layer "B.Fab")
		)
		(fp_line
			(start -0.67945 -0.3048)
			(end -0.67945 0.3048)
			(stroke
				(width 0.1)
				(type default)
			)
			(layer "B.Fab")
		)
		(fp_line
			(start 0.12065 -0.2794)
			(end -0.12065 -0.2794)
			(stroke
				(width 0.1)
				(type default)
			)
			(layer "B.Fab")
		)
		(fp_line
			(start -0.12065 -0.2794)
			(end -0.12065 -0.3048)
			(stroke
				(width 0.1)
				(type default)
			)
			(layer "B.Fab")
		)
		(fp_line
			(start 0.12065 0.2794)
			(end 0.12065 0.3048)
			(stroke
				(width 0.1)
				(type default)
			)
			(layer "B.Fab")
		)
		(fp_line
			(start -0.120396 0.2794)
			(end 0.12065 0.2794)
			(stroke
				(width 0.1)
				(type default)
			)
			(layer "B.Fab")
		)
		(fp_line
			(start 0.67945 0.3048)
			(end 0.67945 -0.305054)
			(stroke
				(width 0.1)
				(type default)
			)
			(layer "B.Fab")
		)
		(fp_line
			(start 0.12065 0.3048)
			(end 0.67945 0.3048)
			(stroke
				(width 0.1)
				(type default)
			)
			(layer "B.Fab")
		)
		(fp_line
			(start -0.120396 0.3048)
			(end -0.120396 0.2794)
			(stroke
				(width 0.1)
				(type default)
			)
			(layer "B.Fab")
		)
		(fp_line
			(start -0.67945 0.3048)
			(end -0.120396 0.3048)
			(stroke
				(width 0.1)
				(type default)
			)
			(layer "B.Fab")
		)
		(pad "1" smd circle
			(at 0.40005 0 270)
			(size 0 0)
			(layers "B.Cu" "B.Mask" "B.Paste")
			(net "P1V2_AUX")
		)
		(pad "2" smd circle
			(at -0.40005 0 270)
			(size 0 0)
			(layers "B.Cu" "B.Mask" "B.Paste")
			(net "GND")
		)
	)
	(footprint ""
		(layer "B.Cu")
		(at 76.869544 -408.517344 90)
		(property "Reference" "C6680"
			(at 0 0 90)
			(layer "B.SilkS")
			(hide yes)
			(effects
				(font
					(size 1.27 1.27)
				)
				(justify mirror)
			)
		)
		(property "Value" ""
			(at 0 0 90)
			(layer "B.Fab")
			(effects
				(font
					(size 1.27 1.27)
				)
				(justify mirror)
			)
		)
		(duplicate_pad_numbers_are_jumpers no)
		(fp_line
			(start 0.299974 -0.150114)
			(end -0.299974 -0.150114)
			(stroke
				(width 0.1)
				(type default)
			)
			(layer "B.Fab")
		)
		(fp_line
			(start -0.299974 -0.150114)
			(end -0.299974 0.150114)
			(stroke
				(width 0.1)
				(type default)
			)
			(layer "B.Fab")
		)
		(fp_line
			(start 0.299974 0.150114)
			(end 0.299974 -0.150114)
			(stroke
				(width 0.1)
				(type default)
			)
			(layer "B.Fab")
		)
		(fp_line
			(start -0.299974 0.150114)
			(end 0.299974 0.150114)
			(stroke
				(width 0.1)
				(type default)
			)
			(layer "B.Fab")
		)
		(pad "1" smd rect
			(at 0.2667 0 270)
			(size 0.3048 0.381)
			(layers "B.Cu" "B.Mask" "B.Paste")
			(net "P5E_CPU1_P1_TX_BUF_C_DN<9>")
		)
		(pad "2" smd rect
			(at -0.2667 0 270)
			(size 0.3048 0.381)
			(layers "B.Cu" "B.Mask" "B.Paste")
			(net "P5E_CPU1_P1_TX_BUF_DN<9>")
		)
	)
	(footprint ""
		(layer "B.Cu")
		(at 94.31909 -390.560052 90)
		(property "Reference" "C339"
			(at 0 0 90)
			(layer "B.SilkS")
			(hide yes)
			(effects
				(font
					(size 1.27 1.27)
				)
				(justify mirror)
			)
		)
		(property "Value" ""
			(at 0 0 90)
			(layer "B.Fab")
			(effects
				(font
					(size 1.27 1.27)
				)
				(justify mirror)
			)
		)
		(duplicate_pad_numbers_are_jumpers no)
		(fp_line
			(start 0.7874 -0.4064)
			(end -0.7874 -0.4064)
			(stroke
				(width 0.1524)
				(type default)
			)
			(layer "B.SilkS")
		)
		(fp_line
			(start -0.7874 -0.4064)
			(end -0.7874 0.4064)
			(stroke
				(width 0.1524)
				(type default)
			)
			(layer "B.SilkS")
		)
		(fp_line
			(start 0.7874 0.4064)
			(end 0.7874 -0.4064)
			(stroke
				(width 0.1524)
				(type default)
			)
			(layer "B.SilkS")
		)
		(fp_line
			(start -0.7874 0.4064)
			(end 0.7874 0.4064)
			(stroke
				(width 0.1524)
				(type default)
			)
			(layer "B.SilkS")
		)
		(fp_line
			(start 0.67945 -0.305054)
			(end 0.12065 -0.305054)
			(stroke
				(width 0.1)
				(type default)
			)
			(layer "B.Fab")
		)
		(fp_line
			(start 0.12065 -0.305054)
			(end 0.12065 -0.2794)
			(stroke
				(width 0.1)
				(type default)
			)
			(layer "B.Fab")
		)
		(fp_line
			(start -0.12065 -0.3048)
			(end -0.67945 -0.3048)
			(stroke
				(width 0.1)
				(type default)
			)
			(layer "B.Fab")
		)
		(fp_line
			(start -0.67945 -0.3048)
			(end -0.67945 0.3048)
			(stroke
				(width 0.1)
				(type default)
			)
			(layer "B.Fab")
		)
		(fp_line
			(start 0.12065 -0.2794)
			(end -0.12065 -0.2794)
			(stroke
				(width 0.1)
				(type default)
			)
			(layer "B.Fab")
		)
		(fp_line
			(start -0.12065 -0.2794)
			(end -0.12065 -0.3048)
			(stroke
				(width 0.1)
				(type default)
			)
			(layer "B.Fab")
		)
		(fp_line
			(start 0.12065 0.2794)
			(end 0.12065 0.3048)
			(stroke
				(width 0.1)
				(type default)
			)
			(layer "B.Fab")
		)
		(fp_line
			(start -0.120396 0.2794)
			(end 0.12065 0.2794)
			(stroke
				(width 0.1)
				(type default)
			)
			(layer "B.Fab")
		)
		(fp_line
			(start 0.67945 0.3048)
			(end 0.67945 -0.305054)
			(stroke
				(width 0.1)
				(type default)
			)
			(layer "B.Fab")
		)
		(fp_line
			(start 0.12065 0.3048)
			(end 0.67945 0.3048)
			(stroke
				(width 0.1)
				(type default)
			)
			(layer "B.Fab")
		)
		(fp_line
			(start -0.120396 0.3048)
			(end -0.120396 0.2794)
			(stroke
				(width 0.1)
				(type default)
			)
			(layer "B.Fab")
		)
		(fp_line
			(start -0.67945 0.3048)
			(end -0.120396 0.3048)
			(stroke
				(width 0.1)
				(type default)
			)
			(layer "B.Fab")
		)
		(pad "1" smd circle
			(at 0.40005 0 270)
			(size 0 0)
			(layers "B.Cu" "B.Mask" "B.Paste")
			(net "P0V9_CPU1_RT1_2A")
		)
		(pad "2" smd circle
			(at -0.40005 0 270)
			(size 0 0)
			(layers "B.Cu" "B.Mask" "B.Paste")
			(net "GND")
		)
	)
)
